(kicad_pcb
	(version 20260206)
	(generator "pcbnew")
	(generator_version "10.0")
	(general
		(thickness 1.6)
		(legacy_teardrops no)
	)
	(paper "A4")
	(title_block
		(title "03242023_DA0F0TMBIJ0_F0T_Motherboard_J_brd_V01_OCP.brd")
		(comment 1 "Grand Teton / footprints 1529-1534 of 6105")
	)
	(layers
		(0 "F.Cu" signal "TOP")
		(4 "In1.Cu" signal "GND")
		(6 "In2.Cu" signal "IN1")
		(8 "In3.Cu" signal "GND1")
		(10 "In4.Cu" signal "IN2")
		(12 "In5.Cu" signal "GND2")
		(14 "In6.Cu" signal "IN3")
		(16 "In7.Cu" signal "GND3")
		(18 "In8.Cu" signal "VCC")
		(20 "In9.Cu" signal "VCC1")
		(22 "In10.Cu" signal "GND4")
		(24 "In11.Cu" signal "IN4")
		(26 "In12.Cu" signal "GND5")
		(28 "In13.Cu" signal "IN5")
		(30 "In14.Cu" signal "GND6")
		(32 "In15.Cu" signal "IN6")
		(34 "In16.Cu" signal "GND7")
		(2 "B.Cu" signal "BOTTOM")
		(9 "F.Adhes" user "F.Adhesive")
		(11 "B.Adhes" user "B.Adhesive")
		(13 "F.Paste" user "Package Geometry/Pastemask Top")
		(15 "B.Paste" user "Package Geometry/Pastemask Bottom")
		(5 "F.SilkS" user "Ref Des/Silkscreen Top")
		(7 "B.SilkS" user "Ref Des/Silkscreen Bottom")
		(1 "F.Mask" user "Board Geometry/Soldermask Top")
		(3 "B.Mask" user "Board Geometry/Soldermask Bottom")
		(17 "Dwgs.User" user "User.Drawings")
		(19 "Cmts.User" user "User.Comments")
		(21 "Eco1.User" user "User.Eco1")
		(23 "Eco2.User" user "User.Eco2")
		(25 "Edge.Cuts" user "Board Geometry/Outline")
		(27 "Margin" user)
		(31 "F.CrtYd" user "Package Geometry/Place Bound Top")
		(29 "B.CrtYd" user "Package Geometry/Place Bound Bottom")
		(35 "F.Fab" user "Ref Des/Assembly Top")
		(33 "B.Fab" user "Ref Des/Assembly Bottom")
	)
	(footprint ""
		(layer "F.Cu")
		(at 304.058828 -364.929928)
		(property "Reference" "PC1669"
			(at 0 0 0)
			(layer "F.SilkS")
			(hide yes)
			(effects
				(font
					(size 1.27 1.27)
				)
			)
		)
		(property "Value" ""
			(at 0 0 0)
			(layer "F.Fab")
			(effects
				(font
					(size 1.27 1.27)
				)
			)
		)
		(duplicate_pad_numbers_are_jumpers no)
		(fp_line
			(start -1.524 -0.762)
			(end 1.524 -0.762)
			(stroke
				(width 0.1524)
				(type default)
			)
			(layer "F.SilkS")
		)
		(fp_line
			(start -1.524 0.762)
			(end -1.524 -0.762)
			(stroke
				(width 0.1524)
				(type default)
			)
			(layer "F.SilkS")
		)
		(fp_line
			(start 1.524 -0.762)
			(end 1.524 0.762)
			(stroke
				(width 0.1524)
				(type default)
			)
			(layer "F.SilkS")
		)
		(fp_line
			(start 1.524 0.762)
			(end -1.524 0.762)
			(stroke
				(width 0.1524)
				(type default)
			)
			(layer "F.SilkS")
		)
		(fp_line
			(start -1.1049 -0.724916)
			(end -1.1049 0.724916)
			(stroke
				(width 0.1)
				(type default)
			)
			(layer "F.Fab")
		)
		(fp_line
			(start -1.1049 0.724916)
			(end 1.1049 0.724916)
			(stroke
				(width 0.1)
				(type default)
			)
			(layer "F.Fab")
		)
		(fp_line
			(start 1.1049 -0.724916)
			(end -1.1049 -0.724916)
			(stroke
				(width 0.1)
				(type default)
			)
			(layer "F.Fab")
		)
		(fp_line
			(start 1.1049 0.724916)
			(end 1.1049 -0.724916)
			(stroke
				(width 0.1)
				(type default)
			)
			(layer "F.Fab")
		)
		(pad "1" smd rect
			(at -0.889 0 180)
			(size 1.016 1.27)
			(layers "F.Cu" "F.Mask" "F.Paste")
			(net "SW_P12V_PVCCFA_EHV_FIVRA_CPU0_L")
		)
		(pad "2" smd rect
			(at 0.889 0 180)
			(size 1.016 1.27)
			(layers "F.Cu" "F.Mask" "F.Paste")
			(net "GND")
		)
	)
	(footprint ""
		(layer "F.Cu")
		(at 78.160626 -151.210772)
		(property "Reference" "R665"
			(at 0 0 0)
			(layer "F.SilkS")
			(hide yes)
			(effects
				(font
					(size 1.27 1.27)
				)
			)
		)
		(property "Value" ""
			(at 0 0 0)
			(layer "F.Fab")
			(effects
				(font
					(size 1.27 1.27)
				)
			)
		)
		(duplicate_pad_numbers_are_jumpers no)
		(fp_line
			(start -0.7874 -0.4064)
			(end 0.7874 -0.4064)
			(stroke
				(width 0.1524)
				(type default)
			)
			(layer "F.SilkS")
		)
		(fp_line
			(start -0.7874 0.4064)
			(end -0.7874 -0.4064)
			(stroke
				(width 0.1524)
				(type default)
			)
			(layer "F.SilkS")
		)
		(fp_line
			(start 0.7874 -0.4064)
			(end 0.7874 0.4064)
			(stroke
				(width 0.1524)
				(type default)
			)
			(layer "F.SilkS")
		)
		(fp_line
			(start 0.7874 0.4064)
			(end -0.7874 0.4064)
			(stroke
				(width 0.1524)
				(type default)
			)
			(layer "F.SilkS")
		)
		(fp_line
			(start -0.67945 -0.305054)
			(end -0.12065 -0.305054)
			(stroke
				(width 0.1)
				(type default)
			)
			(layer "F.Fab")
		)
		(fp_line
			(start -0.67945 0.3048)
			(end -0.67945 -0.305054)
			(stroke
				(width 0.1)
				(type default)
			)
			(layer "F.Fab")
		)
		(fp_line
			(start -0.12065 -0.305054)
			(end -0.12065 -0.2794)
			(stroke
				(width 0.1)
				(type default)
			)
			(layer "F.Fab")
		)
		(fp_line
			(start -0.12065 -0.2794)
			(end 0.12065 -0.2794)
			(stroke
				(width 0.1)
				(type default)
			)
			(layer "F.Fab")
		)
		(fp_line
			(start -0.12065 0.2794)
			(end -0.12065 0.3048)
			(stroke
				(width 0.1)
				(type default)
			)
			(layer "F.Fab")
		)
		(fp_line
			(start -0.12065 0.3048)
			(end -0.67945 0.3048)
			(stroke
				(width 0.1)
				(type default)
			)
			(layer "F.Fab")
		)
		(fp_line
			(start 0.120396 0.2794)
			(end -0.12065 0.2794)
			(stroke
				(width 0.1)
				(type default)
			)
			(layer "F.Fab")
		)
		(fp_line
			(start 0.120396 0.3048)
			(end 0.120396 0.2794)
			(stroke
				(width 0.1)
				(type default)
			)
			(layer "F.Fab")
		)
		(fp_line
			(start 0.12065 -0.3048)
			(end 0.67945 -0.3048)
			(stroke
				(width 0.1)
				(type default)
			)
			(layer "F.Fab")
		)
		(fp_line
			(start 0.12065 -0.2794)
			(end 0.12065 -0.3048)
			(stroke
				(width 0.1)
				(type default)
			)
			(layer "F.Fab")
		)
		(fp_line
			(start 0.67945 -0.3048)
			(end 0.67945 0.3048)
			(stroke
				(width 0.1)
				(type default)
			)
			(layer "F.Fab")
		)
		(fp_line
			(start 0.67945 0.3048)
			(end 0.120396 0.3048)
			(stroke
				(width 0.1)
				(type default)
			)
			(layer "F.Fab")
		)
		(pad "1" smd circle
			(at -0.40005 0)
			(size 0 0)
			(layers "F.Cu" "F.Mask" "F.Paste")
			(net "I3C_SPD_DDRABCD_CPU1_R_SCL")
		)
		(pad "2" smd circle
			(at 0.40005 0)
			(size 0 0)
			(layers "F.Cu" "F.Mask" "F.Paste")
			(net "I3C_SPD_DDRABCD_CPU1_LVC1_R_SCL")
		)
	)
	(footprint ""
		(layer "F.Cu")
		(at 197.41388 -104.955848)
		(property "Reference" "R1206"
			(at 0 0 0)
			(layer "F.SilkS")
			(hide yes)
			(effects
				(font
					(size 1.27 1.27)
				)
			)
		)
		(property "Value" ""
			(at 0 0 0)
			(layer "F.Fab")
			(effects
				(font
					(size 1.27 1.27)
				)
			)
		)
		(duplicate_pad_numbers_are_jumpers no)
		(fp_line
			(start -0.7874 -0.4064)
			(end 0.7874 -0.4064)
			(stroke
				(width 0.1524)
				(type default)
			)
			(layer "F.SilkS")
		)
		(fp_line
			(start -0.7874 0.4064)
			(end -0.7874 -0.4064)
			(stroke
				(width 0.1524)
				(type default)
			)
			(layer "F.SilkS")
		)
		(fp_line
			(start 0.7874 -0.4064)
			(end 0.7874 0.4064)
			(stroke
				(width 0.1524)
				(type default)
			)
			(layer "F.SilkS")
		)
		(fp_line
			(start 0.7874 0.4064)
			(end -0.7874 0.4064)
			(stroke
				(width 0.1524)
				(type default)
			)
			(layer "F.SilkS")
		)
		(fp_line
			(start -0.67945 -0.305054)
			(end -0.12065 -0.305054)
			(stroke
				(width 0.1)
				(type default)
			)
			(layer "F.Fab")
		)
		(fp_line
			(start -0.67945 0.3048)
			(end -0.67945 -0.305054)
			(stroke
				(width 0.1)
				(type default)
			)
			(layer "F.Fab")
		)
		(fp_line
			(start -0.12065 -0.305054)
			(end -0.12065 -0.2794)
			(stroke
				(width 0.1)
				(type default)
			)
			(layer "F.Fab")
		)
		(fp_line
			(start -0.12065 -0.2794)
			(end 0.12065 -0.2794)
			(stroke
				(width 0.1)
				(type default)
			)
			(layer "F.Fab")
		)
		(fp_line
			(start -0.12065 0.2794)
			(end -0.12065 0.3048)
			(stroke
				(width 0.1)
				(type default)
			)
			(layer "F.Fab")
		)
		(fp_line
			(start -0.12065 0.3048)
			(end -0.67945 0.3048)
			(stroke
				(width 0.1)
				(type default)
			)
			(layer "F.Fab")
		)
		(fp_line
			(start 0.120396 0.2794)
			(end -0.12065 0.2794)
			(stroke
				(width 0.1)
				(type default)
			)
			(layer "F.Fab")
		)
		(fp_line
			(start 0.120396 0.3048)
			(end 0.120396 0.2794)
			(stroke
				(width 0.1)
				(type default)
			)
			(layer "F.Fab")
		)
		(fp_line
			(start 0.12065 -0.3048)
			(end 0.67945 -0.3048)
			(stroke
				(width 0.1)
				(type default)
			)
			(layer "F.Fab")
		)
		(fp_line
			(start 0.12065 -0.2794)
			(end 0.12065 -0.3048)
			(stroke
				(width 0.1)
				(type default)
			)
			(layer "F.Fab")
		)
		(fp_line
			(start 0.67945 -0.3048)
			(end 0.67945 0.3048)
			(stroke
				(width 0.1)
				(type default)
			)
			(layer "F.Fab")
		)
		(fp_line
			(start 0.67945 0.3048)
			(end 0.120396 0.3048)
			(stroke
				(width 0.1)
				(type default)
			)
			(layer "F.Fab")
		)
		(pad "1" smd circle
			(at -0.40005 0)
			(size 0 0)
			(layers "F.Cu" "F.Mask" "F.Paste")
			(net "RST_MB_STBY_R_N")
		)
		(pad "2" smd circle
			(at 0.40005 0)
			(size 0 0)
			(layers "F.Cu" "F.Mask" "F.Paste")
			(net "RST_MB_STBY_N")
		)
	)
	(footprint ""
		(layer "F.Cu")
		(at 172.77588 -126.964948 90)
		(property "Reference" "R1404"
			(at 0 0 90)
			(layer "F.SilkS")
			(hide yes)
			(effects
				(font
					(size 1.27 1.27)
				)
			)
		)
		(property "Value" ""
			(at 0 0 90)
			(layer "F.Fab")
			(effects
				(font
					(size 1.27 1.27)
				)
			)
		)
		(duplicate_pad_numbers_are_jumpers no)
		(fp_line
			(start 0.7874 -0.4064)
			(end 0.7874 0.4064)
			(stroke
				(width 0.1524)
				(type default)
			)
			(layer "F.SilkS")
		)
		(fp_line
			(start -0.7874 -0.4064)
			(end 0.7874 -0.4064)
			(stroke
				(width 0.1524)
				(type default)
			)
			(layer "F.SilkS")
		)
		(fp_line
			(start 0.7874 0.4064)
			(end -0.7874 0.4064)
			(stroke
				(width 0.1524)
				(type default)
			)
			(layer "F.SilkS")
		)
		(fp_line
			(start -0.7874 0.4064)
			(end -0.7874 -0.4064)
			(stroke
				(width 0.1524)
				(type default)
			)
			(layer "F.SilkS")
		)
		(fp_line
			(start -0.12065 -0.305054)
			(end -0.12065 -0.2794)
			(stroke
				(width 0.1)
				(type default)
			)
			(layer "F.Fab")
		)
		(fp_line
			(start -0.67945 -0.305054)
			(end -0.12065 -0.305054)
			(stroke
				(width 0.1)
				(type default)
			)
			(layer "F.Fab")
		)
		(fp_line
			(start 0.67945 -0.3048)
			(end 0.67945 0.3048)
			(stroke
				(width 0.1)
				(type default)
			)
			(layer "F.Fab")
		)
		(fp_line
			(start 0.12065 -0.3048)
			(end 0.67945 -0.3048)
			(stroke
				(width 0.1)
				(type default)
			)
			(layer "F.Fab")
		)
		(fp_line
			(start 0.12065 -0.2794)
			(end 0.12065 -0.3048)
			(stroke
				(width 0.1)
				(type default)
			)
			(layer "F.Fab")
		)
		(fp_line
			(start -0.12065 -0.2794)
			(end 0.12065 -0.2794)
			(stroke
				(width 0.1)
				(type default)
			)
			(layer "F.Fab")
		)
		(fp_line
			(start 0.120396 0.2794)
			(end -0.12065 0.2794)
			(stroke
				(width 0.1)
				(type default)
			)
			(layer "F.Fab")
		)
		(fp_line
			(start -0.12065 0.2794)
			(end -0.12065 0.3048)
			(stroke
				(width 0.1)
				(type default)
			)
			(layer "F.Fab")
		)
		(fp_line
			(start 0.67945 0.3048)
			(end 0.120396 0.3048)
			(stroke
				(width 0.1)
				(type default)
			)
			(layer "F.Fab")
		)
		(fp_line
			(start 0.120396 0.3048)
			(end 0.120396 0.2794)
			(stroke
				(width 0.1)
				(type default)
			)
			(layer "F.Fab")
		)
		(fp_line
			(start -0.12065 0.3048)
			(end -0.67945 0.3048)
			(stroke
				(width 0.1)
				(type default)
			)
			(layer "F.Fab")
		)
		(fp_line
			(start -0.67945 0.3048)
			(end -0.67945 -0.305054)
			(stroke
				(width 0.1)
				(type default)
			)
			(layer "F.Fab")
		)
		(pad "1" smd circle
			(at -0.40005 0 90)
			(size 0 0)
			(layers "F.Cu" "F.Mask" "F.Paste")
			(net "FM_PCH_P1V8_AUX_EN")
		)
		(pad "2" smd circle
			(at 0.40005 0 90)
			(size 0 0)
			(layers "F.Cu" "F.Mask" "F.Paste")
			(net "GND")
		)
	)
	(footprint ""
		(layer "F.Cu")
		(at 303.65573 -346.239084 180)
		(property "Reference" "PR587"
			(at 0 0 180)
			(layer "F.SilkS")
			(hide yes)
			(effects
				(font
					(size 1.27 1.27)
				)
			)
		)
		(property "Value" ""
			(at 0 0 180)
			(layer "F.Fab")
			(effects
				(font
					(size 1.27 1.27)
				)
			)
		)
		(duplicate_pad_numbers_are_jumpers no)
		(fp_line
			(start 0.7874 0.4064)
			(end -0.7874 0.4064)
			(stroke
				(width 0.1524)
				(type default)
			)
			(layer "F.SilkS")
		)
		(fp_line
			(start 0.7874 -0.4064)
			(end 0.7874 0.4064)
			(stroke
				(width 0.1524)
				(type default)
			)
			(layer "F.SilkS")
		)
		(fp_line
			(start -0.7874 0.4064)
			(end -0.7874 -0.4064)
			(stroke
				(width 0.1524)
				(type default)
			)
			(layer "F.SilkS")
		)
		(fp_line
			(start -0.7874 -0.4064)
			(end 0.7874 -0.4064)
			(stroke
				(width 0.1524)
				(type default)
			)
			(layer "F.SilkS")
		)
		(fp_line
			(start 0.67945 0.3048)
			(end 0.120396 0.3048)
			(stroke
				(width 0.1)
				(type default)
			)
			(layer "F.Fab")
		)
		(fp_line
			(start 0.67945 -0.3048)
			(end 0.67945 0.3048)
			(stroke
				(width 0.1)
				(type default)
			)
			(layer "F.Fab")
		)
		(fp_line
			(start 0.12065 -0.2794)
			(end 0.12065 -0.3048)
			(stroke
				(width 0.1)
				(type default)
			)
			(layer "F.Fab")
		)
		(fp_line
			(start 0.12065 -0.3048)
			(end 0.67945 -0.3048)
			(stroke
				(width 0.1)
				(type default)
			)
			(layer "F.Fab")
		)
		(fp_line
			(start 0.120396 0.3048)
			(end 0.120396 0.2794)
			(stroke
				(width 0.1)
				(type default)
			)
			(layer "F.Fab")
		)
		(fp_line
			(start 0.120396 0.2794)
			(end -0.12065 0.2794)
			(stroke
				(width 0.1)
				(type default)
			)
			(layer "F.Fab")
		)
		(fp_line
			(start -0.12065 0.3048)
			(end -0.67945 0.3048)
			(stroke
				(width 0.1)
				(type default)
			)
			(layer "F.Fab")
		)
		(fp_line
			(start -0.12065 0.2794)
			(end -0.12065 0.3048)
			(stroke
				(width 0.1)
				(type default)
			)
			(layer "F.Fab")
		)
		(fp_line
			(start -0.12065 -0.2794)
			(end 0.12065 -0.2794)
			(stroke
				(width 0.1)
				(type default)
			)
			(layer "F.Fab")
		)
		(fp_line
			(start -0.12065 -0.305054)
			(end -0.12065 -0.2794)
			(stroke
				(width 0.1)
				(type default)
			)
			(layer "F.Fab")
		)
		(fp_line
			(start -0.67945 0.3048)
			(end -0.67945 -0.305054)
			(stroke
				(width 0.1)
				(type default)
			)
			(layer "F.Fab")
		)
		(fp_line
			(start -0.67945 -0.305054)
			(end -0.12065 -0.305054)
			(stroke
				(width 0.1)
				(type default)
			)
			(layer "F.Fab")
		)
		(pad "1" smd circle
			(at -0.40005 0 180)
			(size 0 0)
			(layers "F.Cu" "F.Mask" "F.Paste")
			(net "VSENSE_PVCCFA_EHV_FIVRA_CPU0_DP")
		)
		(pad "2" smd circle
			(at 0.40005 0 180)
			(size 0 0)
			(layers "F.Cu" "F.Mask" "F.Paste")
			(net "PVCCFA_EHV_FIVRA_CPU0")
		)
	)
	(footprint ""
		(layer "F.Cu")
		(at 50.437542 -166.847266)
		(property "Reference" "PC376"
			(at 0 0 0)
			(layer "F.SilkS")
			(hide yes)
			(effects
				(font
					(size 1.27 1.27)
				)
			)
		)
		(property "Value" ""
			(at 0 0 0)
			(layer "F.Fab")
			(effects
				(font
					(size 1.27 1.27)
				)
			)
		)
		(duplicate_pad_numbers_are_jumpers no)
		(fp_line
			(start -0.7874 -0.4064)
			(end 0.7874 -0.4064)
			(stroke
				(width 0.1524)
				(type default)
			)
			(layer "F.SilkS")
		)
		(fp_line
			(start -0.7874 0.4064)
			(end -0.7874 -0.4064)
			(stroke
				(width 0.1524)
				(type default)
			)
			(layer "F.SilkS")
		)
		(fp_line
			(start 0.7874 -0.4064)
			(end 0.7874 0.4064)
			(stroke
				(width 0.1524)
				(type default)
			)
			(layer "F.SilkS")
		)
		(fp_line
			(start 0.7874 0.4064)
			(end -0.7874 0.4064)
			(stroke
				(width 0.1524)
				(type default)
			)
			(layer "F.SilkS")
		)
		(fp_line
			(start -0.67945 -0.305054)
			(end -0.12065 -0.305054)
			(stroke
				(width 0.1)
				(type default)
			)
			(layer "F.Fab")
		)
		(fp_line
			(start -0.67945 0.3048)
			(end -0.67945 -0.305054)
			(stroke
				(width 0.1)
				(type default)
			)
			(layer "F.Fab")
		)
		(fp_line
			(start -0.12065 -0.305054)
			(end -0.12065 -0.2794)
			(stroke
				(width 0.1)
				(type default)
			)
			(layer "F.Fab")
		)
		(fp_line
			(start -0.12065 -0.2794)
			(end 0.12065 -0.2794)
			(stroke
				(width 0.1)
				(type default)
			)
			(layer "F.Fab")
		)
		(fp_line
			(start -0.12065 0.2794)
			(end -0.12065 0.3048)
			(stroke
				(width 0.1)
				(type default)
			)
			(layer "F.Fab")
		)
		(fp_line
			(start -0.12065 0.3048)
			(end -0.67945 0.3048)
			(stroke
				(width 0.1)
				(type default)
			)
			(layer "F.Fab")
		)
		(fp_line
			(start 0.120396 0.2794)
			(end -0.12065 0.2794)
			(stroke
				(width 0.1)
				(type default)
			)
			(layer "F.Fab")
		)
		(fp_line
			(start 0.120396 0.3048)
			(end 0.120396 0.2794)
			(stroke
				(width 0.1)
				(type default)
			)
			(layer "F.Fab")
		)
		(fp_line
			(start 0.12065 -0.3048)
			(end 0.67945 -0.3048)
			(stroke
				(width 0.1)
				(type default)
			)
			(layer "F.Fab")
		)
		(fp_line
			(start 0.12065 -0.2794)
			(end 0.12065 -0.3048)
			(stroke
				(width 0.1)
				(type default)
			)
			(layer "F.Fab")
		)
		(fp_line
			(start 0.67945 -0.3048)
			(end 0.67945 0.3048)
			(stroke
				(width 0.1)
				(type default)
			)
			(layer "F.Fab")
		)
		(fp_line
			(start 0.67945 0.3048)
			(end 0.120396 0.3048)
			(stroke
				(width 0.1)
				(type default)
			)
			(layer "F.Fab")
		)
		(pad "1" smd circle
			(at -0.40005 0)
			(size 0 0)
			(layers "F.Cu" "F.Mask" "F.Paste")
			(net "SW_PVCCD_HV_CPU1_BOOT1_R")
		)
		(pad "2" smd circle
			(at 0.40005 0)
			(size 0 0)
			(layers "F.Cu" "F.Mask" "F.Paste")
			(net "SW_PVCCD_HV_CPU1_BOOTR1")
		)
	)
)
